(kicad_pcb
	(version 20260206)
	(generator "pcbnew")
	(generator_version "10.0")
	(general
		(thickness 1.6)
		(legacy_teardrops no)
	)
	(paper "A4")
	(title_block
		(title "Bryce Canyon_IOM_IOC_16318-2_OCP.brd")
		(comment 1 "Bryce Canyon / footprints 1347-1355 of 1605")
	)
	(layers
		(0 "F.Cu" signal "TOP")
		(4 "In1.Cu" signal "L2GND")
		(6 "In2.Cu" signal "L3")
		(8 "In3.Cu" signal "L4VCC")
		(10 "In4.Cu" signal "L5VCC")
		(12 "In5.Cu" signal "L6")
		(14 "In6.Cu" signal "L7GND")
		(2 "B.Cu" signal "BOTTOM")
		(9 "F.Adhes" user "F.Adhesive")
		(11 "B.Adhes" user "B.Adhesive")
		(13 "F.Paste" user "Package Geometry/Pastemask Top")
		(15 "B.Paste" user "Package Geometry/Pastemask Bottom")
		(5 "F.SilkS" user "Ref Des/Silkscreen Top")
		(7 "B.SilkS" user "Ref Des/Silkscreen Bottom")
		(1 "F.Mask" user "Board Geometry/Soldermask Top")
		(3 "B.Mask" user "Board Geometry/Soldermask Bottom")
		(17 "Dwgs.User" user "User.Drawings")
		(19 "Cmts.User" user "User.Comments")
		(21 "Eco1.User" user "User.Eco1")
		(23 "Eco2.User" user "User.Eco2")
		(25 "Edge.Cuts" user "Board Geometry/Outline")
		(27 "Margin" user)
		(31 "F.CrtYd" user "Package Geometry/Place Bound Top")
		(29 "B.CrtYd" user "Package Geometry/Place Bound Bottom")
		(35 "F.Fab" user "Ref Des/Assembly Top")
		(33 "B.Fab" user "Ref Des/Assembly Bottom")
	)
	(footprint ""
		(layer "B.Cu")
		(at 195.9356 -66.6623 90)
		(property "Reference" "C390"
			(at 0 0 90)
			(layer "B.SilkS")
			(hide yes)
			(effects
				(font
					(size 1.27 1.27)
				)
				(justify mirror)
			)
		)
		(property "Value" "SC1U16V2KX-7-GP"
			(at -1.7526 -1.6002 90)
			(unlocked yes)
			(layer "B.Fab")
			(hide yes)
			(effects
				(font
					(size 1.016 1.016)
					(thickness 0.1524)
				)
				(justify mirror)
			)
		)
		(property "Device Type" "C402-TO0D2H24"
			(at -1.7526 -3.1242 90)
			(unlocked yes)
			(layer "B.Fab")
			(hide yes)
			(effects
				(font
					(size 1.016 1.016)
					(thickness 0.1524)
				)
				(justify mirror)
			)
		)
		(duplicate_pad_numbers_are_jumpers no)
		(fp_rect
			(start 0.4826 0.889)
			(end -0.4826 -0.889)
			(stroke
				(width 0)
				(type default)
			)
			(fill no)
			(layer "B.CrtYd")
		)
		(fp_rect
			(start 0.4826 0.889)
			(end -0.4826 -0.889)
			(stroke
				(width 0)
				(type default)
			)
			(fill no)
			(layer "B.Fab")
		)
		(pad "1" smd custom
			(at 0 -0.4572 270)
			(size 0.1524 0.1524)
			(layers "B.Cu" "B.Mask" "B.Paste")
			(net "P0V975")
			(options
				(clearance outline)
				(anchor circle)
			)
			(primitives
				(gr_poly
					(pts
						(arc
							(start -0.254 -0.3048)
							(mid -0.325842 -0.275042)
							(end -0.3556 -0.2032)
						)
						(arc
							(start -0.3556 0.2032)
							(mid -0.325842 0.275042)
							(end -0.254 0.3048)
						)
						(arc
							(start 0.254 0.3048)
							(mid 0.325842 0.275042)
							(end 0.3556 0.2032)
						)
						(arc
							(start 0.3556 -0.2032)
							(mid 0.325842 -0.275042)
							(end 0.254 -0.3048)
						)
					)
					(width 0)
					(fill yes)
				)
			)
		)
		(pad "2" smd custom
			(at 0 0.4572 270)
			(size 0.1524 0.1524)
			(layers "B.Cu" "B.Mask" "B.Paste")
			(net "GND")
			(options
				(clearance outline)
				(anchor circle)
			)
			(primitives
				(gr_poly
					(pts
						(arc
							(start -0.254 -0.3048)
							(mid -0.325842 -0.275042)
							(end -0.3556 -0.2032)
						)
						(arc
							(start -0.3556 0.2032)
							(mid -0.325842 0.275042)
							(end -0.254 0.3048)
						)
						(arc
							(start 0.254 0.3048)
							(mid 0.325842 0.275042)
							(end 0.3556 0.2032)
						)
						(arc
							(start 0.3556 -0.2032)
							(mid 0.325842 -0.275042)
							(end 0.254 -0.3048)
						)
					)
					(width 0)
					(fill yes)
				)
			)
		)
	)
	(footprint ""
		(layer "B.Cu")
		(at 192.405 -65.3796 90)
		(property "Reference" "C406"
			(at 0 0 90)
			(layer "B.SilkS")
			(hide yes)
			(effects
				(font
					(size 1.27 1.27)
				)
				(justify mirror)
			)
		)
		(property "Value" "SCD1U6D3V1KX-GP"
			(at 2.8321 -1.7399 90)
			(unlocked yes)
			(layer "B.Fab")
			(hide yes)
			(effects
				(font
					(size 1.016 1.016)
					(thickness 0.1524)
				)
				(justify mirror)
			)
		)
		(property "Device Type" "C0201H13"
			(at 2.8321 -3.2639 90)
			(unlocked yes)
			(layer "B.Fab")
			(hide yes)
			(effects
				(font
					(size 1.016 1.016)
					(thickness 0.1524)
				)
				(justify mirror)
			)
		)
		(duplicate_pad_numbers_are_jumpers no)
		(fp_rect
			(start 0.2794 0.6477)
			(end -0.2794 -0.6477)
			(stroke
				(width 0)
				(type default)
			)
			(fill no)
			(layer "B.CrtYd")
		)
		(fp_rect
			(start 0.2794 0.6477)
			(end -0.2794 -0.6477)
			(stroke
				(width 0)
				(type default)
			)
			(fill no)
			(layer "B.Fab")
		)
		(pad "1" smd custom
			(at 0 -0.2794 270)
			(size 0.0762 0.0762)
			(layers "B.Cu" "B.Mask" "B.Paste")
			(net "P0V975")
			(options
				(clearance outline)
				(anchor circle)
			)
			(primitives
				(gr_poly
					(pts
						(arc
							(start 0.1524 0.127)
							(mid 0.137521 0.162921)
							(end 0.1016 0.1778)
						)
						(arc
							(start -0.1016 0.1778)
							(mid -0.137521 0.162921)
							(end -0.1524 0.127)
						)
						(arc
							(start -0.1524 -0.127)
							(mid -0.137521 -0.162921)
							(end -0.1016 -0.1778)
						)
						(arc
							(start 0.1016 -0.1778)
							(mid 0.137521 -0.162921)
							(end 0.1524 -0.127)
						)
					)
					(width 0)
					(fill yes)
				)
			)
		)
		(pad "2" smd custom
			(at 0 0.2794 270)
			(size 0.0762 0.0762)
			(layers "B.Cu" "B.Mask" "B.Paste")
			(net "GND")
			(options
				(clearance outline)
				(anchor circle)
			)
			(primitives
				(gr_poly
					(pts
						(arc
							(start 0.1524 0.127)
							(mid 0.137521 0.162921)
							(end 0.1016 0.1778)
						)
						(arc
							(start -0.1016 0.1778)
							(mid -0.137521 0.162921)
							(end -0.1524 0.127)
						)
						(arc
							(start -0.1524 -0.127)
							(mid -0.137521 -0.162921)
							(end -0.1016 -0.1778)
						)
						(arc
							(start 0.1016 -0.1778)
							(mid 0.137521 -0.162921)
							(end 0.1524 -0.127)
						)
					)
					(width 0)
					(fill yes)
				)
			)
		)
	)
	(footprint ""
		(layer "B.Cu")
		(at 94.687136 -159.012128 90)
		(property "Reference" "R21"
			(at 0 0 90)
			(layer "B.SilkS")
			(hide yes)
			(effects
				(font
					(size 1.27 1.27)
				)
				(justify mirror)
			)
		)
		(property "Value" "4K7R2F-GP"
			(at -0.064008 -3.993896 90)
			(unlocked yes)
			(layer "B.Fab")
			(hide yes)
			(effects
				(font
					(size 1.016 1.016)
					(thickness 0.1524)
				)
				(justify mirror)
			)
		)
		(property "Device Type" "R402H16"
			(at -0.064008 -5.517896 90)
			(unlocked yes)
			(layer "B.Fab")
			(hide yes)
			(effects
				(font
					(size 1.016 1.016)
					(thickness 0.1524)
				)
				(justify mirror)
			)
		)
		(duplicate_pad_numbers_are_jumpers no)
		(fp_line
			(start 0.508 -0.9398)
			(end 0.508 0.9398)
			(stroke
				(width 0.1524)
				(type default)
			)
			(layer "B.SilkS")
		)
		(fp_line
			(start -0.508 -0.9398)
			(end 0.508 -0.9398)
			(stroke
				(width 0.1524)
				(type default)
			)
			(layer "B.SilkS")
		)
		(fp_rect
			(start 0.508 0.9398)
			(end -0.508 -0.9398)
			(stroke
				(width 0)
				(type default)
			)
			(fill no)
			(layer "B.CrtYd")
		)
		(fp_rect
			(start 0.508 0.9398)
			(end -0.508 -0.9398)
			(stroke
				(width 0)
				(type default)
			)
			(fill no)
			(layer "B.Fab")
		)
		(pad "1" smd custom
			(at 0 -0.4445 270)
			(size 0.1397 0.1397)
			(layers "B.Cu" "B.Mask" "B.Paste")
			(net "P3V3_STBY")
			(options
				(clearance outline)
				(anchor circle)
			)
			(primitives
				(gr_poly
					(pts
						(arc
							(start -0.1778 0.2794)
							(mid -0.249642 0.249642)
							(end -0.2794 0.1778)
						)
						(arc
							(start -0.2794 -0.1778)
							(mid -0.249642 -0.249642)
							(end -0.1778 -0.2794)
						)
						(arc
							(start 0.1778 -0.2794)
							(mid 0.249642 -0.249642)
							(end 0.2794 -0.1778)
						)
						(arc
							(start 0.2794 0.1778)
							(mid 0.249642 0.249642)
							(end 0.1778 0.2794)
						)
					)
					(width 0)
					(fill yes)
				)
			)
		)
		(pad "2" smd custom
			(at 0 0.4445 270)
			(size 0.1397 0.1397)
			(layers "B.Cu" "B.Mask" "B.Paste")
			(net "USB_RESET_N")
			(options
				(clearance outline)
				(anchor circle)
			)
			(primitives
				(gr_poly
					(pts
						(arc
							(start -0.1778 0.2794)
							(mid -0.249642 0.249642)
							(end -0.2794 0.1778)
						)
						(arc
							(start -0.2794 -0.1778)
							(mid -0.249642 -0.249642)
							(end -0.1778 -0.2794)
						)
						(arc
							(start 0.1778 -0.2794)
							(mid 0.249642 -0.249642)
							(end 0.2794 -0.1778)
						)
						(arc
							(start 0.2794 0.1778)
							(mid 0.249642 0.249642)
							(end 0.1778 0.2794)
						)
					)
					(width 0)
					(fill yes)
				)
			)
		)
	)
	(footprint ""
		(layer "B.Cu")
		(at 191.383666 -52.810156)
		(property "Reference" "TP150"
			(at 0 0 0)
			(layer "B.SilkS")
			(hide yes)
			(effects
				(font
					(size 1.27 1.27)
				)
				(justify mirror)
			)
		)
		(property "Value" "TPAD28-2-GP"
			(at 0.0127 -1.6637 0)
			(unlocked yes)
			(layer "B.Fab")
			(hide yes)
			(effects
				(font
					(size 1.016 1.016)
					(thickness 0.1524)
				)
				(justify mirror)
			)
		)
		(property "Device Type" "TPAD28"
			(at 0.0127 -3.1877 0)
			(unlocked yes)
			(layer "B.Fab")
			(hide yes)
			(effects
				(font
					(size 1.016 1.016)
					(thickness 0.1524)
				)
				(justify mirror)
			)
		)
		(duplicate_pad_numbers_are_jumpers no)
		(fp_poly
			(pts
				(arc
					(start 0.3556 0)
					(mid -0.3556 0)
					(end 0.3556 0)
				)
			)
			(stroke
				(width 0)
				(type default)
			)
			(fill no)
			(layer "B.CrtYd")
		)
		(fp_poly
			(pts
				(arc
					(start 0.6096 0)
					(mid -0.6096 0)
					(end 0.6096 0)
				)
			)
			(stroke
				(width 0)
				(type default)
			)
			(fill no)
			(layer "B.Fab")
		)
		(pad "1" smd circle
			(at 0 0 180)
			(size 0.7112 0.7112)
			(layers "B.Cu" "B.Mask" "B.Paste")
			(net "JTAG_IOC_TCK")
		)
	)
	(footprint ""
		(layer "B.Cu")
		(at 191.1858 -54.3814)
		(property "Reference" "TP153"
			(at 0 0 0)
			(layer "B.SilkS")
			(hide yes)
			(effects
				(font
					(size 1.27 1.27)
				)
				(justify mirror)
			)
		)
		(property "Value" "TPAD28-2-GP"
			(at 0.0127 -1.6637 0)
			(unlocked yes)
			(layer "B.Fab")
			(hide yes)
			(effects
				(font
					(size 1.016 1.016)
					(thickness 0.1524)
				)
				(justify mirror)
			)
		)
		(property "Device Type" "TPAD28"
			(at 0.0127 -3.1877 0)
			(unlocked yes)
			(layer "B.Fab")
			(hide yes)
			(effects
				(font
					(size 1.016 1.016)
					(thickness 0.1524)
				)
				(justify mirror)
			)
		)
		(duplicate_pad_numbers_are_jumpers no)
		(fp_poly
			(pts
				(arc
					(start 0.3556 0)
					(mid -0.3556 0)
					(end 0.3556 0)
				)
			)
			(stroke
				(width 0)
				(type default)
			)
			(fill no)
			(layer "B.CrtYd")
		)
		(fp_poly
			(pts
				(arc
					(start 0.6096 0)
					(mid -0.6096 0)
					(end 0.6096 0)
				)
			)
			(stroke
				(width 0)
				(type default)
			)
			(fill no)
			(layer "B.Fab")
		)
		(pad "1" smd circle
			(at 0 0 180)
			(size 0.7112 0.7112)
			(layers "B.Cu" "B.Mask" "B.Paste")
			(net "IOC_TDO")
		)
	)
	(footprint ""
		(layer "B.Cu")
		(at 184.1754 -116.0526 90)
		(property "Reference" "C275"
			(at 0 0 90)
			(layer "B.SilkS")
			(hide yes)
			(effects
				(font
					(size 1.27 1.27)
				)
				(justify mirror)
			)
		)
		(property "Value" "SC10U16V5KX-7-GP-U"
			(at 0.0762 -6.1214 90)
			(unlocked yes)
			(layer "B.Fab")
			(hide yes)
			(effects
				(font
					(size 1.016 1.016)
					(thickness 0.1524)
				)
				(justify mirror)
			)
		)
		(property "Device Type" "C805H58"
			(at 0.0762 -8.1534 90)
			(unlocked yes)
			(layer "B.Fab")
			(hide yes)
			(effects
				(font
					(size 1.016 1.016)
					(thickness 0.1524)
				)
				(justify mirror)
			)
		)
		(duplicate_pad_numbers_are_jumpers no)
		(fp_line
			(start -0.635 0)
			(end 0.635 0)
			(stroke
				(width 0.508)
				(type default)
			)
			(layer "B.SilkS")
		)
		(fp_rect
			(start 0.9652 1.778)
			(end -0.9652 -1.778)
			(stroke
				(width 0)
				(type default)
			)
			(fill no)
			(layer "B.CrtYd")
		)
		(fp_poly
			(pts
				(xy 0.9652 -1.778) (xy -0.9652 -1.778) (xy -0.9652 1.778) (xy 0.9652 1.778)
			)
			(stroke
				(width 0)
				(type default)
			)
			(fill no)
			(layer "B.Fab")
		)
		(pad "1" smd rect
			(at 0 -0.9652 270)
			(size 1.397 1.143)
			(layers "B.Cu" "B.Mask" "B.Paste")
			(net "VT235_VDDH")
		)
		(pad "2" smd rect
			(at 0 0.9652 270)
			(size 1.397 1.143)
			(layers "B.Cu" "B.Mask" "B.Paste")
			(net "GND")
		)
	)
	(footprint ""
		(layer "B.Cu")
		(at 201.092308 -52.334668 -90)
		(property "Reference" "C336"
			(at 0 0 90)
			(layer "B.SilkS")
			(hide yes)
			(effects
				(font
					(size 1.27 1.27)
				)
				(justify mirror)
			)
		)
		(property "Value" "SCD1U6D3V1KX-GP"
			(at 2.8321 -1.7399 270)
			(unlocked yes)
			(layer "B.Fab")
			(hide yes)
			(effects
				(font
					(size 1.016 1.016)
					(thickness 0.1524)
				)
				(justify mirror)
			)
		)
		(property "Device Type" "C0201H13"
			(at 2.8321 -3.2639 270)
			(unlocked yes)
			(layer "B.Fab")
			(hide yes)
			(effects
				(font
					(size 1.016 1.016)
					(thickness 0.1524)
				)
				(justify mirror)
			)
		)
		(duplicate_pad_numbers_are_jumpers no)
		(fp_rect
			(start 0.2794 0.6477)
			(end -0.2794 -0.6477)
			(stroke
				(width 0)
				(type default)
			)
			(fill no)
			(layer "B.CrtYd")
		)
		(fp_rect
			(start 0.2794 0.6477)
			(end -0.2794 -0.6477)
			(stroke
				(width 0)
				(type default)
			)
			(fill no)
			(layer "B.Fab")
		)
		(pad "1" smd custom
			(at 0 -0.2794 90)
			(size 0.0762 0.0762)
			(layers "B.Cu" "B.Mask" "B.Paste")
			(net "SYS_PLL_VDD")
			(options
				(clearance outline)
				(anchor circle)
			)
			(primitives
				(gr_poly
					(pts
						(arc
							(start 0.1524 0.127)
							(mid 0.137521 0.162921)
							(end 0.1016 0.1778)
						)
						(arc
							(start -0.1016 0.1778)
							(mid -0.137521 0.162921)
							(end -0.1524 0.127)
						)
						(arc
							(start -0.1524 -0.127)
							(mid -0.137521 -0.162921)
							(end -0.1016 -0.1778)
						)
						(arc
							(start 0.1016 -0.1778)
							(mid 0.137521 -0.162921)
							(end 0.1524 -0.127)
						)
					)
					(width 0)
					(fill yes)
				)
			)
		)
		(pad "2" smd custom
			(at 0 0.2794 90)
			(size 0.0762 0.0762)
			(layers "B.Cu" "B.Mask" "B.Paste")
			(net "GND")
			(options
				(clearance outline)
				(anchor circle)
			)
			(primitives
				(gr_poly
					(pts
						(arc
							(start 0.1524 0.127)
							(mid 0.137521 0.162921)
							(end 0.1016 0.1778)
						)
						(arc
							(start -0.1016 0.1778)
							(mid -0.137521 0.162921)
							(end -0.1524 0.127)
						)
						(arc
							(start -0.1524 -0.127)
							(mid -0.137521 -0.162921)
							(end -0.1016 -0.1778)
						)
						(arc
							(start 0.1016 -0.1778)
							(mid 0.137521 -0.162921)
							(end 0.1524 -0.127)
						)
					)
					(width 0)
					(fill yes)
				)
			)
		)
	)
	(footprint ""
		(layer "B.Cu")
		(at 12.7762 -148.9329 -90)
		(property "Reference" "C63"
			(at 0 0 90)
			(layer "B.SilkS")
			(hide yes)
			(effects
				(font
					(size 1.27 1.27)
				)
				(justify mirror)
			)
		)
		(property "Value" "SC4D7U25V5KX-1-GP"
			(at 0.0762 -6.1214 270)
			(unlocked yes)
			(layer "B.Fab")
			(hide yes)
			(effects
				(font
					(size 1.016 1.016)
					(thickness 0.1524)
				)
				(justify mirror)
			)
		)
		(property "Device Type" "C805H58"
			(at 0.0762 -8.1534 270)
			(unlocked yes)
			(layer "B.Fab")
			(hide yes)
			(effects
				(font
					(size 1.016 1.016)
					(thickness 0.1524)
				)
				(justify mirror)
			)
		)
		(duplicate_pad_numbers_are_jumpers no)
		(fp_line
			(start -0.635 0)
			(end 0.635 0)
			(stroke
				(width 0.508)
				(type default)
			)
			(layer "B.SilkS")
		)
		(fp_rect
			(start 0.9652 1.778)
			(end -0.9652 -1.778)
			(stroke
				(width 0)
				(type default)
			)
			(fill no)
			(layer "B.CrtYd")
		)
		(fp_poly
			(pts
				(xy 0.9652 -1.778) (xy -0.9652 -1.778) (xy -0.9652 1.778) (xy 0.9652 1.778)
			)
			(stroke
				(width 0)
				(type default)
			)
			(fill no)
			(layer "B.Fab")
		)
		(pad "1" smd rect
			(at 0 -0.9652 90)
			(size 1.397 1.143)
			(layers "B.Cu" "B.Mask" "B.Paste")
			(net "P1V2_STBY")
		)
		(pad "2" smd rect
			(at 0 0.9652 90)
			(size 1.397 1.143)
			(layers "B.Cu" "B.Mask" "B.Paste")
			(net "GND")
		)
	)
	(footprint ""
		(layer "B.Cu")
		(at 89.916 -161.2646 180)
		(property "Reference" "C16"
			(at 0 0 0)
			(layer "B.SilkS")
			(hide yes)
			(effects
				(font
					(size 1.27 1.27)
				)
				(justify mirror)
			)
		)
		(property "Value" "SC1U16V3KX-5GP"
			(at 0 -2.8194 180)
			(unlocked yes)
			(layer "B.Fab")
			(hide yes)
			(effects
				(font
					(size 1.016 1.016)
					(thickness 0.1524)
				)
				(justify mirror)
			)
		)
		(property "Device Type" "C603H36"
			(at 0 -4.3434 180)
			(unlocked yes)
			(layer "B.Fab")
			(hide yes)
			(effects
				(font
					(size 1.016 1.016)
					(thickness 0.1524)
				)
				(justify mirror)
			)
		)
		(duplicate_pad_numbers_are_jumpers no)
		(fp_line
			(start -0.508 0)
			(end 0.508 0)
			(stroke
				(width 0.2032)
				(type default)
			)
			(layer "B.SilkS")
		)
		(fp_rect
			(start 0.5842 1.3335)
			(end -0.5842 -1.3335)
			(stroke
				(width 0)
				(type default)
			)
			(fill no)
			(layer "B.CrtYd")
		)
		(fp_rect
			(start 0.5842 1.3335)
			(end -0.5842 -1.3335)
			(stroke
				(width 0)
				(type default)
			)
			(fill no)
			(layer "B.Fab")
		)
		(pad "1" smd custom
			(at 0 -0.762)
			(size 0.2159 0.2159)
			(layers "B.Cu" "B.Mask" "B.Paste")
			(net "P3V3_STBY")
			(options
				(clearance outline)
				(anchor circle)
			)
			(primitives
				(gr_poly
					(pts
						(arc
							(start -0.3302 0.4318)
							(mid -0.402042 0.402042)
							(end -0.4318 0.3302)
						)
						(arc
							(start -0.4318 -0.3302)
							(mid -0.402042 -0.402042)
							(end -0.3302 -0.4318)
						)
						(arc
							(start 0.3302 -0.4318)
							(mid 0.402042 -0.402042)
							(end 0.4318 -0.3302)
						)
						(arc
							(start 0.4318 0.3302)
							(mid 0.402042 0.402042)
							(end 0.3302 0.4318)
						)
					)
					(width 0)
					(fill yes)
				)
			)
		)
		(pad "2" smd custom
			(at 0 0.762)
			(size 0.2159 0.2159)
			(layers "B.Cu" "B.Mask" "B.Paste")
			(net "GND")
			(options
				(clearance outline)
				(anchor circle)
			)
			(primitives
				(gr_poly
					(pts
						(arc
							(start -0.3302 0.4318)
							(mid -0.402042 0.402042)
							(end -0.4318 0.3302)
						)
						(arc
							(start -0.4318 -0.3302)
							(mid -0.402042 -0.402042)
							(end -0.3302 -0.4318)
						)
						(arc
							(start 0.3302 -0.4318)
							(mid 0.402042 -0.402042)
							(end 0.4318 -0.3302)
						)
						(arc
							(start 0.4318 0.3302)
							(mid 0.402042 0.402042)
							(end 0.3302 0.4318)
						)
					)
					(width 0)
					(fill yes)
				)
			)
		)
	)
)
